                    - SPARES  LIST -

MOSFET_NCH_DUAL-NX6008NBKS,SMLA
    Q105  2
     Q99  2
MOSFET_NCH_DUAL-PJT138K,SMLF,IA
    Q106  2

                    - PART SUMMARY -

74CBTLV3126PW-74CBTLV3126PW,SMA	AL003126K08	8
74LVC1G02GW_SMLF-74LVC1G02GW,IA	ALVC1G02000	1
74LVC1G07GV-74LVC1G07GV,SMLF,IA	AL1G0007001	4
74LVC1G07SE7-74LVC1G07SE-7,SMLA	AL1G07SE000	2
74LVC1G08W57-74LVC1G08W5-7,SMLA	AL1G0008020	9
74LVC1G126SE7-74LVC1G126SE-7,SA	AL1G0126009	9
74LVC1G17GW-74LVC1G17GW,SMLF,IA	AL1G0017K01	2
74LVC1G32GW_SMLF-74LVC1G32GW,IA	ALVC1G32007	1
74LVC1G66GV-74LVC1G66GV,SMLF,IA	AL001G66000	3
74LVC2G07DW7-74LVC2G07DW-7,SMLA	AL002G07003	8
74LVC2G07DW7-74LVC2G07DW-7,SMLB	AL002G07003	1
74LVC2G08DP-74LVC2G08DP,SMLF,IA	ALVC2G08K01	3
74LVC2G17GW-74LVC2G17GW,SMLF,IA	AL2G0017005	7
9FGL0251DKILFT-9FGL0251DKILFT,A	AL000251002	1
9QXL2001BNHGI8-9QXL2001BNHGI8,A	AJ020010003	1
9SQ440NQQI8-9SQ440NQQI8,SMLF,IA	AJ004400000	1
9ZXL0451EKILFT-9ZXL0451EKILFT,A	AL000451003	1
ADC128D818CIMTXNOPB-ADC128D818A	AL000128K00	1
ADM1086AKSZREEL7-ADM1086AKSZ-RA	AL001086001	1
AP331AWG7-AP331AWG-7,SMLF,EMPTA	AL000331011	4
APX80929SAG7-APX809-29SAG-7,SMA	AL080929000	4
BAS70057F-BAS70-05-7-F,SMLF,ICA	BC0BAS70Z01	1
BAT547F-BAT547F,SMLF,IC,BC0BATA	BC0BAT54Z53	1
BC847BPN-BC847BPN,SMLF,IC,BA00A	BA008470026	6
CONN112_10137002101LF-CONN112_A	DFHSB2FR012	7
CONN14_210HP207GBR1-CONN14_210A	DFHD14MS170	1
CONN160_10131762101LF-CONN160_A	DFHSG0FR007	1
CONN1_10165288101LF-CONN1_1016A	DFHS03FR030	2
CONN2_AAABAT029Y19-CONN2_AAA-BA	DFHS02FR062	1
CONN3_210HP1030BR1-CONN3_210-HA	DFHD03MS213	2
CONN3_210HP1030BR1-CONN3_210-HB	DFHD03MS213	6
CONN60_101062636003K02LF-CONN6A	DFHD60MR024	1
CONN8_210HP1080BR1-CONN8_210-HA	DFHD08MS392	1
DIODE_TVS-SMF14A,SMLF,IC,BCSMFA	BCSMF14AZ01	4
DS125BR111RTWR-DS125BR111RTWR,A	AL000125003	1
DUMMY_SYMBOL-BATTERY_SYMBOL,MEA	DUMMY12	1
DUMMY_SYMBOL-MECHANIC_SYMBOL,MA	DUMMY10	1
EMMITSBURG_REV0P9-GFNOCPU04302A	AJ0QV2N0T00	1
GL852GOHY60-GL852G-OHY60,SMLF,A	AL000852001	1
GL852GOHY60-GL852G-OHY60,SMLF,B	AL000852001	1
GND_HOLE_TH-EMPTY,GND_HOLE140	GND_HOLE140	2
GND_HOLE_TH-EMPTY,GND_HOLE514	GND_HOLE514	1
GND_HOLE_TH-EMPTY,TMP-QGND_HOLA	TMP-QGND_HOLE12	2
GTL2014PW-GTL2014PW,SMLF,IC,ALA	AL002014K01	6
HOLE_TH-EMPTY,DUMMY50	DUMMY50	4
HOLE_TH-EMPTY,HOLE1079	HOLE1079	12
HOLE_TH-EMPTY,HOLE1187	HOLE1187	2
HOLE_TH-EMPTY,HOLE1195	HOLE1195	1
HOLE_TH-EMPTY,HOLE1247	HOLE1247	2
HOLE_TH-EMPTY,HOLE1248	HOLE1248	2
HOLE_TH-EMPTY,HOLE372	HOLE372	1
HOLE_TH-EMPTY,HOLE596	HOLE596	21
HOLE_TH-EMPTY,SP_HOLE1199	HOLE1199	4
HOLE_TH-EMPTY,TMP-C_T2I_ALEX_1A	TMP-C_T2I_ALEX_1121_1	6
HOLE_TH-EMPTY,TMP-Q_HOLE78	TMP-Q_HOLE78	2
INA183A1IDBVR-INA183A1IDBVR,SMA	AL000183000	2
INA230AIRGTR-INA230AIRGTR,SMLFA	AL000230001	1
INA230AIRGTR-INA230AIRGTR,SMLFB	AL000230001	5
IR3889MTRPBF-IR3889MTRPBF,SMLFA	AL003889000	1
ISL69260IRAZT-ISL69260IRAZ-T,SA	AL069260000	4
ISL99390FRZTR5935-ISL99390FRZ-A	AL099390004	30
LCMXO3LF9400C5BG484C-LCMXO3LF-A	AJ094000T08	1
LM4040AIM3X25NOPB-LM4040AIM3X-A	AL404025013	4
LM75BD-LM75BD,SMLF,IC,AL0075BDA	AL0075BD000	4
LT6700CS61TRPBF-LT6700CS6-1#TRA	AL006700001	1
LTC4307CMS8-LTC4307CMS8,SMLF,EA	AL004307000	1
LTC4307CMS8-LTC4307CMS8,SMLF,IA	AL004307000	4
M24128BWMN6TP-M24128-BWMN6TP,SA	AKE30Z00613	1
MAX11617EEET-MAX11617EEE+T,SMLA	AL011617W00	1
MAX15090BEWIT-MAX15090BEWI+T,SA	AL015080B00	4
MAX15090BEWIT-MAX15090BEWI+T,SB	AL015080B00	3
ME_DUMMY_SYMBOL-CBS_3X558-8,MEA	DUMMY47	1
ME_DUMMY_SYMBOL-EFI BIOS LABELA	DUMMY28_HCLU2002010	1
ME_DUMMY_SYMBOL-PB-E1_SMALL,MEA	DUMMY3	1
ME_DUMMY_SYMBOL-PCB_VENDOR_LOGA	DUMMY7	1
ME_DUMMY_SYMBOL-PICKUP_SMDC20,A	DUMMY48	10
ME_DUMMY_SYMBOL-QUANTA_LOGO_7XA	DUMMY1	1
ME_DUMMY_SYMBOL-SNLABEL_15X5,MA	DUMMY36	1
ME_DUMMY_SYMBOL-SNLABEL_27X6,MA	DUMMY46	1
ME_DUMMY_SYMBOL-WEEE,MECH,EMPTA	DUMMY2	1
MMBT3904_SMLF-MMBT3904    ,EMPA	BA039040039	1
MOSFET_NCH_1D3S-PSMNR58-30YLH,A	BAMNR580000	2
MOSFET_NCH_1D3S-PSMNR58-30YLH,B	BAMNR580000	7
MOSFET_NCH_DUAL-NX6008NBKS,SMLA	BAM60080000	5
MOSFET_NCH_DUAL-PJT138K,SMLF,EA	BAM138K0003	4
MOSFET_NCH_DUAL-PJT138K,SMLF,IA	BAM138K0003	55
MOSFET_NCH_GDS_ESD_PROTECTED-2A	BAM70020002	11
MOSFET_NCH_GDS_ESD_PROTECTED-2B	BAM70020002	1
MOSFET_N_SMLF-BSS138K,BSS138K,A	BAM138K0000	7
MOSFET_N_SMLF-BSS138K,BSS138K,B	BAM138K0000	2
MP5016GQHLZ-MP5016GQH-L-Z,SMLFA	AL005016007	3
MP5990GMA1111Z-MP5990GMA-1111-A	AL005990A03	1
MP5991GLUZ-MP5991GLU-Z,SMLF,ICA	AL005991A00	4
NB682GDZ-NB682GD-Z,SMLF,IC,AL0A	AL000682001	1
NC7SB3157_SMLF-NC7SB3157P6X,NCA	ALSB3157000	6
NC7SB3157_SMLF-NC7SB3157P6X,NCB	ALSB3157000	4
NCT7718W-NCT7718W,SMLF,EMPTY,AA	AL007718001	1
NX3L2267GM-NX3L2267GM,SMLF,IC,A	AL002267000	2
PCA9306DP1-PCA9306DP1,SMLF,IC,A	AL009306K04	1
PCA9517AD-PCA9517AD,SMLF,IC,ALA	AL009517000	2
PCA9539RPW-PCA9539RPW,SMLF,IC,A	AL009539K07	1
PCA9545APW-PCA9545APW,SMLF,IC,A	AL009545K17	1
PCA9555APW-PCA9555APW,SMLF,IC,A	AL009555K07	2
PCA9617ADP-PCA9617ADP,SMLF,IC,A	AL009617K02	6
PI3EQX1002EZREX-PI3EQX1002EZREA	AL001002007	1
PI3EQX12902AZLEX-PI3EQX12902AZA	AL012902001	1
PI6CV304LE-PI6CV304LE,SMLF,IC,A	AL000304K01	1
PICOPROBE_BXA-DELTA-L 4.0,SMLFA	TP33	32
QS3VH257QG8_SMLF-QS3VH257QG8,IA	AL000257W24	2
Q_CAPP_SMLF-100UF,16V,20%,OSCOA	CC71003MZ30	1
Q_CAPP_SMLF-220UF,6.3V,20%,ALUA	CC72201MZ28	1
Q_CAPP_SMLF-330UF,2.5V,+10/-35A	CH733LY8802	8
Q_CAPP_SMLF-330UF,2.5V,+10/-35B	CH733LY8802	10
Q_CAPP_SMLF-330UF,2V,35%,SPCAPA	CH733RY8807	8
Q_CAPP_THLF-270UF,16V,20%,OSCOA	CC72703MD38	20
Q_CAPP_THLF-560UF,2.5V,20%,OSCA	CC7560JMD16	36
Q_CAPP_THLF-560UF,6.3V,20%,OSCA	CC75601MD16	4
Q_CAP_0402-0.01UF,25V,10%,X7R,A	CH31004KB17	5
Q_CAP_0402-0.022UF,16V,10%,X7RA	CH32203KB11	3
Q_CAP_0402-0.068UF,16V,10%,EMPA	CH3683K1B09	3
Q_CAP_0402-0.068UF,16V,10%,X7RA	CH3683K1B09	5
Q_CAP_0402-0.1UF,25V,10%,EMPTYA	CH4104K1B00	43
Q_CAP_0402-0.1UF,25V,10%,X7R,CA	CH4104K1B00	280
Q_CAP_0402-0.22UF,16V,10%,X7R,A	CH4223K1B00	4
Q_CAP_0402-1000PF,50V,5%,EMPTYA	CH21006JB10	46
Q_CAP_0402-1000PF,50V,5%,X7R,TA	CH21006JB10	12
Q_CAP_0402-100PF,50V,5%,EMPTY,A	CH11006JB18	11
Q_CAP_0402-100PF,50V,5%,NPO,CHA	CH11006JB00	2
Q_CAP_0402-100PF,50V,5%,X7R,CHA	CH11006JB18	1
Q_CAP_0402-18PF,50V,5%,C0G,CH0A	CH01806JB07	4
Q_CAP_0402-1NF,50V,10%,EMPTY,CA	CH21006KB16	5
Q_CAP_0402-1UF,6.3V,10%,EMPTY,A	CH5101K1B01	6
Q_CAP_0402-220PF,50V,10%,EMPTYA	CH12206KB14	3
Q_CAP_0402-220PF,50V,10%,X7R,TA	CH12206KB14	2
Q_CAP_0402-27PF  ,50V ,5% ,EMPA	CH02706JB06	2
Q_CAP_0402-3300PF,50V,10%,X7R,A	CH2336K1B12	44
Q_CAP_0402-470PF,50V,10%,X7R,TA	CH14706KB18	10
Q_CAP_0402-47PF,50V,5%,NPO,TMPA	CH04706JB01	1
Q_CAP_0402-680PF,50V,10%,X7R,TA	CH16806KB17	4
Q_CAP_0603-1000PF,50V,10%,EMPTA	CH21006K917	1
Q_CAP_C0201-0.1UF,6.3V,10%,X6SA	CH4101KEE01	6
Q_CAP_C0201-0.22UF,6.3V,10%,X6A	CH4221KEE00	2
Q_CAP_C0402-0.001UF,50V,10%,X7A	CH30106KB19	1
Q_CAP_C0402-0.01UF,50V,10%,EMPA	CH31006KB18	7
Q_CAP_C0402-0.01UF,50V,10%,X7RA	CH31006KB18	46
Q_CAP_C0402-0.047UF,25V,10%,X7A	CH3474K1B04	17
Q_CAP_C0402-0.22UF,25V,10%,X7RA	CH4224K1B01	11
Q_CAP_C0402-100NF,50V,10%,EMPTA	CH4106K1B01	17
Q_CAP_C0402-100NF,50V,10%,X7R,A	CH4106K1B01	71
Q_CAP_C0402-10UF,6.3V,20%,EMPTA	CH6101MEB01	1
Q_CAP_C0402-10UF,6.3V,20%,X6S,A	CH6101MEB01	20
Q_CAP_C0402-10UF,6.3V,20%,X6S,B	CH6101MEB03	88
Q_CAP_C0402-12PF,50V,5%,EMPTY,A	CH01206JB05	2
Q_CAP_C0402-1UF,16V,10%,X6S,CHA	CH5103KEB01	62
Q_CAP_C0402-1UF,25V,10%,EMPTY,A	CH5104KEB02	28
Q_CAP_C0402-1UF,25V,10%,X6S,CHA	CH5104KEB02	65
Q_CAP_C0402-2.2UF,10V,10%,X6S,A	CH5222KEB01	68
Q_CAP_C0402-2.2UF,6.3V,20%,X6SA	CH5221MEB00	32
Q_CAP_C0402-22UF,4V,20%,X6S,CHA	CH622KMEB01	137
Q_CAP_C0402-33NF,25V,10%,EMPTYA	CH3334K1B00	1
Q_CAP_C0402-3900PF,50V,10%,EMPA	CH23906KB14	4
Q_CAP_C0402-39PF,50V,5%,EMPTY,A	CH0396J0B04	3
Q_CAP_C0402-560PF,50V,10%,X7R,A	CH1566K1B09	2
Q_CAP_C0402-6800PF,50V,10%,X7RA	CH2686K1B01	3
Q_CAP_C0402-680PF,50V,10%,X7R,A	CH1686K1B09	1
Q_CAP_C0402-8.2PF,50V,0.1P,NP0A	CH-8216TB09	4
Q_CAP_C0603-10UF,4V,20%,EMPTY,A	CH610KME907	2
Q_CAP_C0603-10UF,6.3V,20%,X6S,A	CH6101ME900	18
Q_CAP_C0603-2.2UF,16V,10%,X6S,A	CH5223KE901	1
Q_CAP_C0603-2.2UF,16V,20%,X7R,A	CH5223M1900	4
Q_CAP_C0603-22UF,4V,20%,X6S,CHA	CH622KME901	10
Q_CAP_C0603-22UF,6.3V,20%,X6S,A	CH6221ME900	6
Q_CAP_C0603-4.7UF,16V,10%,X6S,A	CH5473KE902	2
Q_CAP_C0603-47UF,2.5V,20%,X6S,A	CH647LME900	16
Q_CAP_C0805-10UF,16V,10%,EMPTYA	CH6103KEA00	4
Q_CAP_C0805-10UF,16V,10%,EMPTYB	CH6103KEA01	3
Q_CAP_C0805-10UF,16V,10%,X6S,CA	CH6103KEA00	69
Q_CAP_C0805-10UF,16V,10%,X6S,CB	CH6103KEA01	5
Q_CAP_C0805-10UF,16V,10%,X6S,CC	CH6103KEA03	5
Q_CAP_C0805-10UF,25V,10%,X6S,CA	CH6104KEA00	3
Q_CAP_C0805-22UF,10V,20%,X6S,CA	CH6222MEA01	5
Q_CAP_C0805-22UF,16V,20%,X6S,CA	CH6223MEA01	136
Q_CAP_C0805-22UF,16V,20%,X6S,CB	CH6223MEA00	5
Q_CAP_C0805-22UF,16V,20%,X6S,CC	CH6223MEA03	3
Q_CAP_C0805-22UF,4V,20%,X6S,CHA	CH622KMEA03	85
Q_CAP_C0805-47UF,4V,20%,X6S,CHA	CH647KMEA04	195
Q_CAP_C0805-47UF,6.3V,20%,X6S,A	CH6471MEA02	2
Q_CAP_DIFFBUS_C0201-DIFF BUS_0A	CH4221MEE01	374
Q_CAP_DIFFBUS_C0402-DIFF BUS_0A	CH4331KEB01	2
Q_CRYSTAL_SMLF-32.768KHZ,IC,BGA	BG632768012	1
Q_DIODE_SMLF-SDMK0340L-7-F,IC,A	BC000340033	1
Q_FUSE_SMLF-20A/125V,IC,DKK00XA	DKK00XFU000	1
Q_INDUCTOR4P_14-150NH,SMLF,INDA	CV+15^0TZ04	16
Q_INDUCTOR_SMLF-0.68UH,IND,CV+A	CV+68F5MZ05	2
Q_INDUCTOR_SMLF-1.5UH/53A,IND,A	CV-15^0MZ02	1
Q_INDUCTOR_SMLF-100NH/16A,IND,A	CV+10G0MZ04	8
Q_INDUCTOR_SMLF-120NH/69A,IND,A	CV+12^0EZ03	8
Q_INDUCTOR_SMLF-130NH/106A,INDA	CV+13^0KZ11	8
Q_INDUCTOR_SMLF-2.2UH,IND,CV-2A	CV-2280MZ15	1
Q_INDUCTOR_SMLF-300NH/33A,IND,A	CV+30Y0KZ05	3
Q_INDUCTOR_SMLF-4.7UH,IND,CV-4A	CV-47A0MZ10	1
Q_INDUCTOR_SMLF-4.7UH,IND,CV-4B	CV-4755MZ12	2
Q_INDUCTOR_SMLF-50NH/148A,IND,A	CVA50^0EZ01	2
Q_INDUCTOR_SMLF-BLM15PX121SN1DA	CX5PX121001	1
Q_INDUCTOR_SMLF-BLM15PX121SN1DB	CX5PX121001	1
Q_INDUCTOR_SMLF-BLM18PG121SN1DA	CX8PG121009	1
Q_INDUCTOR_SMLF-BLM18PG300SN1DA	CX8PG300001	1
Q_INDUCTOR_SMLF-BLM18PG300SN1DB	CX8PG300001	1
Q_INDUCTOR_SMLF-BLM18SG331TN1DA	CX8SG331000	2
Q_INDUCTOR_SMLF-BLM18SN220TN1DA	CX220TN1001	2
Q_INDUCTOR_SMLF-FCM2012KF-601TA	CX601T05003	6
Q_LED_SMLF-LED_BLUE,LTST-C281TA	BEBL0172Z00	38
Q_LED_SMLF-LED_YELLOW,LTST-C19A	BEYL0159Z00	2
Q_OSC4P_SMLF-25MHZ,OSC,BF62500A	BF625000014	1
Q_OSC4P_SMLF-50MHZ,OSC,BF65000A	BF650000032	1
Q_RES_0402LF-0,5%,1/16W,CHIP,CA	CS00002JB13	579
Q_RES_0402LF-0,5%,1/16W,EMPTY,A	CS00002JB13	154
Q_RES_0402LF-1,1%,1/16W,CHIP,CA	CS-1002FB04	8
Q_RES_0402LF-1,1%,1/16W,EMPTY,A	CS-1002FB04	8
Q_RES_0402LF-1.21K,1%,1/16W,CHA	CS21212FB05	1
Q_RES_0402LF-1.33K,1%,1/16W,EMA	CS21332FB05	3
Q_RES_0402LF-1.5K,1%,1/16W,CHIA	CS21502FB07	14
Q_RES_0402LF-1.5K,1%,1/16W,EMPA	CS21502FB07	1
Q_RES_0402LF-10,1%,1/16W,CHIP,A	CS01002FB07	37
Q_RES_0402LF-10,1%,1/16W,EMPTYA	CS01002FB07	21
Q_RES_0402LF-10.5K,1%,1/16W,EMA	CS31052FB03	2
Q_RES_0402LF-100,1%,1/16W,CHIPA	CS11002FB07	93
Q_RES_0402LF-100,1%,1/16W,EMPTA	CS11002FB07	9
Q_RES_0402LF-100K,1%,1/16W,CHIA	CS41002FB09	45
Q_RES_0402LF-100K,1%,1/16W,EMPA	CS41002FB09	55
Q_RES_0402LF-10K,0.1%,1/16W,CHA	CS31002BB06	1
Q_RES_0402LF-10K,1%,1/16W,CHIPA	CS31002FB08	275
Q_RES_0402LF-10K,1%,1/16W,EMPTA	CS31002FB08	107
Q_RES_0402LF-10M,1%,1/16W,CHIPA	CS61002FB02	3
Q_RES_0402LF-10M,1%,1/16W,EMPTA	CS61002FB02	4
Q_RES_0402LF-11.3K,0.1%,1/16W,A	CS31132BB02	2
Q_RES_0402LF-11.8K,0.1%,1/16W,A	CS31182BB06	1
Q_RES_0402LF-113,1%,1/16W,CHIPA	CS11132FB02	1
Q_RES_0402LF-12.4K,0.1%,1/16W,A	CS31242BB10	2
Q_RES_0402LF-120,1%,1/16W,CHIPA	CS11202FB02	1
Q_RES_0402LF-120K,1%,1/16W,CHIA	CS41202FB05	9
Q_RES_0402LF-127K,1%,1/16W,CHIA	CS41272FB07	4
Q_RES_0402LF-12K,1%,1/16W,EMPTA	CS31202FB04	1
Q_RES_0402LF-130,1%,1/16W,CHIPA	CS11302FB03	34
Q_RES_0402LF-14.3K,1%,1/16W,CHA	CS31432FB02	2
Q_RES_0402LF-15.4K,1%,1/16W,CHA	CS31542FB02	4
Q_RES_0402LF-150,1%,1/16W,CHIPA	CS11502FB07	18
Q_RES_0402LF-150K,1%,1/16W,CHIA	CS41502FB04	1
Q_RES_0402LF-15K,0.1%,1/16W,CHA	CS31502BB03	1
Q_RES_0402LF-15K,1%,1/16W,CHIPA	CS31502FB05	3
Q_RES_0402LF-15K,1%,1/16W,EMPTA	CS31502FB05	4
Q_RES_0402LF-16.9K,1%,1/16W,CHA	CS31692FB03	2
Q_RES_0402LF-160K,1%,1/16W,EMPA	CS41602FB05	7
Q_RES_0402LF-17.4K,1%,1/16W,CHA	CS31742FB04	2
Q_RES_0402LF-17.8K,1%,1/16W,EMA	CS31782FB04	3
Q_RES_0402LF-18K,1%,1/16W,CHIPA	CS31802FB04	1
Q_RES_0402LF-196K,1%,1/16W,CHIA	CS41962FB03	4
Q_RES_0402LF-1K,1%,1/16W,CHIP,A	CS21002FB06	190
Q_RES_0402LF-1K,1%,1/16W,EMPTYA	CS21002FB06	120
Q_RES_0402LF-1M,1%,1/16W,CHIP,A	CS51002FB05	3
Q_RES_0402LF-1M,1%,1/16W,EMPTYA	CS51002FB05	2
Q_RES_0402LF-2.2,1%,1/16W,CHIPA	CS-2202FB01	32
Q_RES_0402LF-2.21K,1%,1/16W,EMA	CS22212FB06	1
Q_RES_0402LF-2.2K,5%,1/16W,CHIA	CS22202JB07	20
Q_RES_0402LF-2.2K,5%,1/16W,EMPA	CS22202JB07	18
Q_RES_0402LF-2.49K,1%,1/16W,CHA	CS22492FB05	2
Q_RES_0402LF-2.67K,1%,1/16W,EMA	CS22672FB03	1
Q_RES_0402LF-2.8K,1%,1/16W,EMPA	CS22802FB04	1
Q_RES_0402LF-200,1%,1/16W,CHIPA	CS12002FB06	11
Q_RES_0402LF-200,1%,1/16W,EMPTA	CS12002FB06	2
Q_RES_0402LF-200K,1%,1/16W,CHIA	CS42002FB05	4
Q_RES_0402LF-200K,1%,1/16W,EMPA	CS42002FB05	5
Q_RES_0402LF-20K,1%,1/16W,CHIPA	CS32002FB06	6
Q_RES_0402LF-20K,1%,1/16W,EMPTA	CS32002FB06	1
Q_RES_0402LF-21.5K,1%,1/16W,CHA	CS32152FB04	1
Q_RES_0402LF-22,1%,1/16W,CHIP,A	CS02202FB02	23
Q_RES_0402LF-22,1%,1/16W,EMPTYA	CS02202FB02	5
Q_RES_0402LF-22,5%,1/16W,CHIP,A	CS02202JB09	1
Q_RES_0402LF-22.6K,1%,1/16W,CHA	CS32262FB02	1
Q_RES_0402LF-23.2K,1%,1/16W,CHA	CS32322FB03	4
Q_RES_0402LF-24.3K,1%,1/16W,CHA	CS32432FB03	2
Q_RES_0402LF-240,1%,1/16W,CHIPA	CS12402FB01	19
Q_RES_0402LF-240,1%,1/16W,EMPTA	CS12402FB01	52
Q_RES_0402LF-249,1%,1/16W,CHIPA	CS12492FB02	4
Q_RES_0402LF-25.5K,1%,1/16W,CHA	CS32552FB06	3
Q_RES_0402LF-26.1K,0.1%,1/16W,A	CS32612BB02	2
Q_RES_0402LF-26.7K,1%,1/16W,CHA	CS32672FB03	2
Q_RES_0402LF-27.4,1%,1/16W,CHIA	CS02742FB03	4
Q_RES_0402LF-28K,1%,1/16W,EMPTA	CS32802FB05	6
Q_RES_0402LF-2K,0.1%,1/16W,CHIA	CS22002BB07	10
Q_RES_0402LF-2K,1%,1/16W,CHIP,A	CS22002FB07	39
Q_RES_0402LF-2K,1%,1/16W,EMPTYA	CS22002FB07	20
Q_RES_0402LF-3.3,1%,1/16W,CHIPA	CS-3302FB01	32
Q_RES_0402LF-3.57K,1%,1/16W,CHA	CS23572FB05	1
Q_RES_0402LF-3.9K,5%,1/16W,EMPA	CS23902JB04	2
Q_RES_0402LF-30.1K,1%,1/16W,CHA	CS33012FB03	3
Q_RES_0402LF-30.1K,1%,1/16W,EMA	CS33012FB03	2
Q_RES_0402LF-301,1%,1/16W,CHIPA	CS13012FB02	8
Q_RES_0402LF-31.6K,1%,1/16W,CHA	CS33162FB02	1
Q_RES_0402LF-33.2,1%,1/16W,CHIA	CS03322FB03	388
Q_RES_0402LF-33.2,1%,1/16W,EMPA	CS03322FB03	8
Q_RES_0402LF-33K,1%,1/16W,CHIPA	CS33302FB00	1
Q_RES_0402LF-34.8K,1%,1/16W,CHA	CS33482FB04	1
Q_RES_0402LF-35.7K,1%,1/16W,CHA	CS33572FB01	4
Q_RES_0402LF-38.3K,0.1%,1/16W,A	CS33832BB06	2
Q_RES_0402LF-4.32K,1%,1/16W,CHA	CS24322FB03	4
Q_RES_0402LF-4.53K,1%,1/16W,CHA	CS24532FB03	2
Q_RES_0402LF-4.75K,1%,1/16W,CHA	CS24752FB03	16
Q_RES_0402LF-4.75K,1%,1/16W,EMA	CS24752FB03	7
Q_RES_0402LF-4.7K,1%,1/16W,CHIA	CS24702FB06	36
Q_RES_0402LF-4.7K,1%,1/16W,EMPA	CS24702FB06	33
Q_RES_0402LF-4.7K,5%,1/16W,CHIA	CS24702JB10	101
Q_RES_0402LF-4.7K,5%,1/16W,EMPA	CS24702JB10	28
Q_RES_0402LF-4.99K,0.1%,1/16W,A	CS24992BB04	2
Q_RES_0402LF-4.99K,1%,1/16W,EMA	CS24992FB07	1
Q_RES_0402LF-46.4K,1%,1/16W,CHA	CS34642FB02	1
Q_RES_0402LF-470,1%,1/16W,CHIPA	CS14702FB04	3
Q_RES_0402LF-47K,0.1%,1/16W,CHA	CS34702BB05	1
Q_RES_0402LF-47K,0.1%,1/16W,EMA	CS34702BB05	2
Q_RES_0402LF-49.9,1%,1/16W,CHIA	CS04992FB07	75
Q_RES_0402LF-49.9,1%,1/16W,EMPA	CS04992FB07	12
Q_RES_0402LF-499,1%,1/16W,CHIPA	CS14992FB06	24
Q_RES_0402LF-5.1,5%,1/16W,CHIPA	CS-5102JB02	1
Q_RES_0402LF-5.11K,1%,1/16W,CHA	CS25112FB04	4
Q_RES_0402LF-5.11K,1%,1/16W,EMA	CS25112FB04	2
Q_RES_0402LF-5.23K,1%,1/16W,CHA	CS25232FB08	1
Q_RES_0402LF-5.36K,1%,1/16W,CHA	CS25362FB02	2
Q_RES_0402LF-510K,5%,1/16W,EMPA	CS45102JB03	1
Q_RES_0402LF-54.9K,1%,1/16W,CHA	CS35492FB03	20
Q_RES_0402LF-54.9K,1%,1/16W,EMA	CS35492FB03	8
Q_RES_0402LF-560,1%,1/16W,CHIPA	CS15602FB03	10
Q_RES_0402LF-56K,1%,1/16W,CHIPA	CS35602FB00	1
Q_RES_0402LF-6.19K,1%,1/16W,CHA	CS26192FB03	2
Q_RES_0402LF-6.8K,1%,1/16W,EMPA	CS26802FB02	4
Q_RES_0402LF-60.4,1%,1/16W,CHIA	CS06042FB03	1
Q_RES_0402LF-60.4K,1%,1/16W,CHA	CS36042FB04	2
Q_RES_0402LF-63.4K,1%,1/16W,CHA	CS36342FB04	1
Q_RES_0402LF-680,1%,1/16W,CHIPA	CS16802FB03	1
Q_RES_0402LF-680,1%,1/16W,EMPTA	CS16802FB03	1
Q_RES_0402LF-681,1%,1/16W,CHIPA	CS16812FB02	1
Q_RES_0402LF-68K,1%,1/16W,CHIPA	CS36802FB04	2
Q_RES_0402LF-68K,1%,1/16W,EMPTA	CS36802FB04	8
Q_RES_0402LF-7.15K,1%,1/16W,CHA	CS27152FB03	3
Q_RES_0402LF-7.32K,0.1%,1/16W,A	CS27322BB09	1
Q_RES_0402LF-7.87K,1%,1/16W,CHA	CS27872FB02	1
Q_RES_0402LF-71.5K,1%,1/16W,EMA	CS37152FB05	7
Q_RES_0402LF-75,1%,1/16W,CHIP,A	CS07502FB04	6
Q_RES_0402LF-75,1%,1/16W,EMPTYA	CS07502FB04	1
Q_RES_0402LF-75K,0.1%,1/16W,CHA	CS37502BB01	2
Q_RES_0402LF-8.25K,0.1%,1/16W,A	CS28252BB01	2
Q_RES_0402LF-8.45K,1%,1/16W,CHA	CS28452FB06	2
Q_RES_0402LF-8.45K,1%,1/16W,EMA	CS28452FB06	1
Q_RES_0402LF-8.87K,1%,1/16W,EMA	CS28872FB01	32
Q_RES_0402LF-82K,1%,1/16W,CHIPA	CS38202FB01	1
Q_RES_0402LF-84.5K,1%,1/16W,CHA	CS38452FB05	4
Q_RES_0402LF-845,1%,1/16W,EMPTA	CS18452FB01	2
Q_RES_0402LF-86.6K,1%,1/16W,EMA	CS38662FB05	1
Q_RES_0402LF-88.7K,1%,1/16W,CHA	CS38872FB18	1
Q_RES_0402LF-9.09K,1%,1/16W,CHA	CS29092FB05	1
Q_RES_0402LF-9.31K,1%,1/16W,EMA	CS29312FB02	1
Q_RES_0402LF-9.76K,1%,1/16W,CHA	CS29762FB05	3
Q_RES_0603LF-1,1%,1/10W,CHIP,CA	CS-1003F900	12
Q_RES_0603LF-10M,1%,1/10W,CHIPA	CS61003F901	1
Q_RES_0603LF-2.2,1%,1/10W,CHIPA	CS-2203F902	2
Q_RES_0603LF-200K,0.1%,1/10W,EA	CS42003B902	1
Q_RES_0603LF-49.9,1%,1/10W,CHIA	CS04993F909	4
Q_RES_0805LF-0,5%,1/8W,CHIP,CSA	CS00004JA05	1
Q_RES_0805LF-0,5%,1/8W,EMPTY,CA	CS00004JA05	1
Q_RES_1206LF-0,,1/2W,CHIP,CS00A	CS00007T200	2
Q_RES_1206LF-0,,1/2W,EMPTY,CS0A	CS00007T200	2
Q_RES_1206LF-243,1%,1/4W,CHIP,A	CS12436F201	4
Q_RES_2512LF-0.01,1%,1W,CHIP,CA	CS+0108F128	5
Q_RES_2512LF-0.03,0.1%,1W,EMPTA	CS+0308BR00	2
Q_RES_4P_12-0.001,1%,3W,SMLF,CA	CS+001DFR10	2
Q_RES_4P_12-0.003,1%,3W,SMLF,EA	CS+003DFR03	1
Q_SHORT_SM-EMPTY,SHORT6	SHORT6	16
Q_SP_RES4P-0.0003,1%,4W,SMLF,EA	CS0000FFT04	4
Q_XTAL_4P_13BI_24GND-12MHZ,SMLA	BG6120000E0	1
Q_XTAL_4P_13BI_24GND-12MHZ,SMLB	BG6120000E0	1
Q_XTAL_4P_13BI_24GND-25MHZ,SMLA	BG625000802	1
Q_XTAL_4P_13BI_24GND-25MHZ,SMLB	BG6250000F0	2
RAA2213404GNPHB0-RAA2213404GNPA	AL221340002	2
RAA229126GNPHA0-RAA229126GNP#HA	AL229126000	2
RS31312R-RS31312R,SMLF,IC,AL03A	AL031312000	4
RS53317LR-RS53317LR,SMLF,IC,ALA	AL053317005	2
RS53318LR-RS53318LR,SMLF,IC,ALA	AL053318002	3
RS53319LR-RS53319LR,SMLF,IC,ALA	AL053319002	1
RT9818C44GV-RT9818C-44GV,SMLF,A	AL009818001	1
SCHOTTKY_12-1N5819HW,SMLF,IC,BA	BC005819Z40	1
SCHOTTKY_12-B0530WS7F,SMLF,IC,A	BC000530Z41	8
SCHOTTKY_AC-B340A-13-F,SMLF,ICA	BC000340Z30	7
SCONN168_ME1016810202011-SCONNA	DFHSG8FR011	3
SCONN20_513860200CV01-SCONN20_A	DFHD20MS193	1
SCONN21_9193031121LF-SCONN21_9A	DFHS21FS003	1
SCONN288_ADR50017P087CC-SCONN2A	DFHST8FS460	16
SCONN288_ADR50017P130CC-SCONN2A	DFHST8FS461	16
SCONN56_123276793-SCONN56_1-23A	DFHS56FS022	1
SCONN60_ASP21410801-SCONN60_ASA	DFHS60FS108	1
SCONN75K_APCI0155P004A-SCONN75A	DFHS75FR313	1
SN74LVC2G07DCKR_SMLF-SN74LVC2GA	AL002G07006	1
SOCKET4677_AZIF0045P001C01CS-SA	DGA^7000023	2
SS15P3SM386A-SS15P3S-M3/86A,SMA	BC015P3SZ00	1
SW_PUSHBUTTON4P_24-SW4S_DTSM-6A	DHP00061N15	1
TCA9548APWR-TCA9548APWR,SMLF,IA	AL009548K02	2
TDR_3P_TH2-EMPTY,N_A	N_A	16
TPS3700DDCR-TPS3700DDCR,SMLF,EA	AL003700002	2
TPS3895ADRYR-TPS3895ADRYR,SMLFA	AL003895003	1
TP_TDR_4P_FTS_TH-TP_TDR_4P_DIPA	N_A	44
TP_TP_BOM ONLY-NA,TP12_BOM	TP12_BOM	10
TUSB211IRWBR-TUSB211IRWBR,SMLFA	AL000211007	2
ZENER_AC-5.0SMDJ14A,SMLF,IC,BCA	BC0MDJ14000	2

Total                                    6093
